# S9S_MB_2U (Grand Teton) — schematic netlist excerpt (pin names and nets, part order shuffled) for the footprints in the layout excerpt that follows; sources: Cadence DE-HDL packaged netlist, KiCad conversion of 03242023_DA0F0TMBIJ0_F0T_Motherboard_J_brd_V01_OCP.brd

J10  SCONN288_ADR50017P087CC  SCONN288_ADR50017-P087CC IO  pkg DDR288S_1-1VXB  page 91
  VIN_BULK0  = P12V_S3_AUX_CPU0_NVDIMM
  RFU0  = TP_CHE_CPU0_DIMM2_FRU_0
  VIN_MGMT  = P3V3_AUX
  HSCL  = I3C_SPD_DDREFGH_CPU0_LVC1_SCL_1
  HSDA  = I3C_SPD_DDREFGH_CPU0_LVC1_SDA
  VSS0  = GND
  DQ0_A  = M_E_CPU0_SA_DQ<0>
  VSS1  = GND
  DQ1_A  = M_E_CPU0_SA_DQ<1>
  VSS2  = GND
  DQS0_A_T  = M_E_CPU0_SA_DQS_DP<0>
  DQS0_A_C  = M_E_CPU0_SA_DQS_DN<0>
  VSS3  = GND
  DQ4_A  = M_E_CPU0_SA_DQ<4>
  VSS4  = GND
  DQ5_A  = M_E_CPU0_SA_DQ<5>
  VSS5  = GND
  DQ8_A  = M_E_CPU0_SA_DQ<8>
  VSS6  = GND
  DQ9_A  = M_E_CPU0_SA_DQ<9>
  VSS7  = GND
  DQS1_A_T  = M_E_CPU0_SA_DQS_DP<1>
  DQS1_A_C  = M_E_CPU0_SA_DQS_DN<1>
  VSS8  = GND
  DQ12_A  = M_E_CPU0_SA_DQ<12>
  VSS9  = GND
  DQ13_A  = M_E_CPU0_SA_DQ<13>
  VSS10  = GND
  DQ16_A  = M_E_CPU0_SA_DQ<16>
  VSS11  = GND
  DQ17_A  = M_E_CPU0_SA_DQ<17>
  VSS12  = GND
  DQS2_A_T  = M_E_CPU0_SA_DQS_DP<2>
  DQS2_A_C  = M_E_CPU0_SA_DQS_DN<2>
  VSS13  = GND
  DQ20_A  = M_E_CPU0_SA_DQ<20>
  VSS14  = GND
  DQ21_A  = M_E_CPU0_SA_DQ<21>
  VSS15  = GND
  DQ24_A  = M_E_CPU0_SA_DQ<24>
  VSS16  = GND
  DQ25_A  = M_E_CPU0_SA_DQ<25>
  VSS17  = GND
  DQS3_A_T  = M_E_CPU0_SA_DQS_DP<3>
  DQS3_A_C  = M_E_CPU0_SA_DQS_DN<3>
  VSS18  = GND
  DQ28_A  = M_E_CPU0_SA_DQ<28>
  VSS19  = GND
  DQ29_A  = M_E_CPU0_SA_DQ<29>
  VSS20  = GND
  CB0_A  = M_E_CPU0_SA_CB<0>
  VSS21  = GND
  CB1_A  = M_E_CPU0_SA_CB<1>
  VSS22  = GND
  DQS4_A_T  = M_E_CPU0_SA_DQS_DP<4>
  DQS4_A_C  = M_E_CPU0_SA_DQS_DN<4>
  VSS23  = GND
  CB4_A  = M_E_CPU0_SA_CB<4>
  VSS24  = GND
  CB5_A  = M_E_CPU0_SA_CB<5>
  VSS25  = GND
  ALERT_N  = M_E_CPU0_ALERT_N
  VSS26  = GND
  CS0_A_N  = M_E_CPU0_SA_CS_N<2>
  VSS27  = GND
  CA0_A  = M_E_CPU0_SA_CA<0>
  VSS28  = GND
  CA2_A  = M_E_CPU0_SA_CA<2>
  VSS29  = GND
  CA4_A  = M_E_CPU0_SA_CA<4>
  VSS30  = GND
  CA6_A  = M_E_CPU0_SA_CA<6>
  VSS31  = GND
  PAR_A  = M_E_CPU0_SA_PAR
  VSS32  = GND
  CA0_B  = M_E_CPU0_SB_CA<0>
  VSS33  = GND
  CA2_B  = M_E_CPU0_SB_CA<2>
  VSS34  = GND
  CA4_B  = M_E_CPU0_SB_CA<4>
  VSS35  = GND
  CA6_B  = M_E_CPU0_SB_CA<6>
  VSS36  = GND
  CS0_B_N  = M_E_CPU0_SB_CS_N<2>
  VSS37  = GND
  \lbd||rsp_a_n\  = M_E_CPU0_SA_RSP<1>
  \lbs||rsp_b_n\  = M_E_CPU0_SB_RSP<1>
  VSS38  = GND
  CB4_B  = M_E_CPU0_SB_CB<4>
  VSS39  = GND
  CB5_B  = M_E_CPU0_SB_CB<5>
  VSS40  = GND
  \dqs9_b_t||tdqs9_b_t||dbi4_b_n\  = M_E_CPU0_SB_DQS_DP<9>
  \dqs9_b_c||tdqs9_b_c\  = M_E_CPU0_SB_DQS_DN<9>
  VSS41  = GND
  CB0_B  = M_E_CPU0_SB_CB<0>
  VSS42  = GND
  CB1_B  = M_E_CPU0_SB_CB<1>
  VSS43  = GND
  DQ0_B  = M_E_CPU0_SB_DQ<0>
  VSS44  = GND
  DQ1_B  = M_E_CPU0_SB_DQ<1>
  VSS45  = GND
  DQS0_B_T  = M_E_CPU0_SB_DQS_DP<0>
  DQS0_B_C  = M_E_CPU0_SB_DQS_DN<0>
  VSS46  = GND
  DQ4_B  = M_E_CPU0_SB_DQ<4>
  VSS47  = GND
  DQ5_B  = M_E_CPU0_SB_DQ<5>
  VSS48  = GND
  DQ8_B  = M_E_CPU0_SB_DQ<8>
  VSS49  = GND
  DQ9_B  = M_E_CPU0_SB_DQ<9>
  VSS50  = GND
  DQS1_B_T  = M_E_CPU0_SB_DQS_DP<1>
  DQS1_B_C  = M_E_CPU0_SB_DQS_DN<1>
  VSS51  = GND
  DQ12_B  = M_E_CPU0_SB_DQ<12>
  VSS52  = GND
  DQ13_B  = M_E_CPU0_SB_DQ<13>
  VSS53  = GND
  DQ16_B  = M_E_CPU0_SB_DQ<16>
  VSS54  = GND
  DQ17_B  = M_E_CPU0_SB_DQ<17>
  VSS55  = GND
  DQS2_B_T  = M_E_CPU0_SB_DQS_DP<2>
  DQS2_B_C  = M_E_CPU0_SB_DQS_DN<2>
  VSS56  = GND
  DQ20_B  = M_E_CPU0_SB_DQ<20>
  VSS57  = GND
  DQ21_B  = M_E_CPU0_SB_DQ<21>
  VSS58  = GND
  DQ24_B  = M_E_CPU0_SB_DQ<24>
  VSS59  = GND
  DQ25_B  = M_E_CPU0_SB_DQ<25>
  VSS60  = GND
  DQS3_B_T  = M_E_CPU0_SB_DQS_DP<3>
  DQS3_B_C  = M_E_CPU0_SB_DQS_DN<3>
  VSS61  = GND
  DQ28_B  = M_E_CPU0_SB_DQ<28>
  VSS62  = GND
  DQ29_B  = M_E_CPU0_SB_DQ<29>
  VSS63  = GND
  RFU1  = TP_CHE_CPU0_DIMM2_FRU_1
  VIN_BULK1  = P12V_S3_AUX_CPU0_NVDIMM
  VIN_BULK2  = P12V_S3_AUX_CPU0_NVDIMM
  \pwr_good||fail_n\  = PWRGD_CHE_CPU0_DIMM2
  HSA  = PD_CHE_CPU0_DIMM2_SAA
  RFU2  = TP_CHE_CPU0_DIMM2_FRU_2
  RFU3  = TP_CHE_CPU0_DIMM2_FRU_3
  VSS64  = GND
  DQ2_A  = M_E_CPU0_SA_DQ<2>
  VSS65  = GND
  DQ3_A  = M_E_CPU0_SA_DQ<3>
  VSS66  = GND
  \dqs5_a_c||tdqs5_a_c||dqs5_a_t||tdqs5_a_t\  = M_E_CPU0_SA_DQS_DN<5>
  \dqs5_a_t||tdqs5_a_t\  = M_E_CPU0_SA_DQS_DP<5>
  VSS67  = GND
  DQ6_A  = M_E_CPU0_SA_DQ<6>
  VSS68  = GND
  DQ7_A  = M_E_CPU0_SA_DQ<7>
  VSS69  = GND
  DQ10_A  = M_E_CPU0_SA_DQ<10>
  VSS70  = GND
  DQ11_A  = M_E_CPU0_SA_DQ<11>
  VSS71  = GND
  \dqs6_a_c||tdqs6_a_c||dqs6_a_t||tdqs6_a_t\  = M_E_CPU0_SA_DQS_DN<6>
  \dqs6_a_t||tdqs6_a_t\  = M_E_CPU0_SA_DQS_DP<6>
  VSS72  = GND
  DQ14_A  = M_E_CPU0_SA_DQ<14>
  VSS73  = GND
  DQ15_A  = M_E_CPU0_SA_DQ<15>
  VSS74  = GND
  DQ18_A  = M_E_CPU0_SA_DQ<18>
  VSS75  = GND
  DQ19_A  = M_E_CPU0_SA_DQ<19>
  VSS76  = GND
  \dqs7_a_c||tdqs7_a_c\  = M_E_CPU0_SA_DQS_DN<7>
  \dqs7_a_t||tdqs7_a_t\  = M_E_CPU0_SA_DQS_DP<7>
  VSS77  = GND
  DQ22_A  = M_E_CPU0_SA_DQ<22>
  VSS78  = GND
  DQ23_A  = M_E_CPU0_SA_DQ<23>
  VSS79  = GND
  DQ26_A  = M_E_CPU0_SA_DQ<26>
  VSS80  = GND
  DQ27_A  = M_E_CPU0_SA_DQ<27>
  VSS81  = GND
  \dqs8_a_c||tdqs8_a_c\  = M_E_CPU0_SA_DQS_DN<8>
  \dqs8_a_t||tdqs8_a_t\  = M_E_CPU0_SA_DQS_DP<8>
  VSS82  = GND
  DQ30_A  = M_E_CPU0_SA_DQ<30>
  VSS83  = GND
  DQ31_A  = M_E_CPU0_SA_DQ<31>
  VSS84  = GND
  CB2_A  = M_E_CPU0_SA_CB<2>
  VSS85  = GND
  CB3_A  = M_E_CPU0_SA_CB<3>
  VSS86  = GND
  \dqs9_a_c||tdqs9_a_c\  = M_E_CPU0_SA_DQS_DN<9>
  \dqs9_a_t||tdqs9_a_t\  = M_E_CPU0_SA_DQS_DP<9>
  VSS87  = GND
  CB6_A  = M_E_CPU0_SA_CB<6>
  VSS88  = GND
  CB7_A  = M_E_CPU0_SA_CB<7>
  VSS89  = GND
  RESET_N  = RST_M_EF_CPU0_FPGA_N
  VSS90  = GND
  CS1_A_N  = M_E_CPU0_SA_CS_N<3>
  VSS91  = GND
  CA1_A  = M_E_CPU0_SA_CA<1>
  VSS92  = GND
  CA3_A  = M_E_CPU0_SA_CA<3>
  VSS93  = GND
  CA5_A  = M_E_CPU0_SA_CA<5>
  VSS94  = GND
  CK_T  = M_E_CPU0_CLK_DP<1>
  CK_C  = M_E_CPU0_CLK_DN<1>
  VSS95  = GND
  RFU4  = TP_CHE_CPU0_DIMM2_FRU_4
  CA1_B  = M_E_CPU0_SB_CA<1>
  VSS96  = GND
  CA3_B  = M_E_CPU0_SB_CA<3>
  VSS97  = GND
  CA5_B  = M_E_CPU0_SB_CA<5>
  VSS98  = GND
  PAR_B  = M_E_CPU0_SB_PAR
  VSS99  = GND
  CS1_B_N  = M_E_CPU0_SB_CS_N<3>
  VSS100  = GND
  RFU5  = TP_CHE_CPU0_DIMM2_FRU_5
  RFU6  = TP_CHE_CPU0_DIMM2_FRU_6
  VSS101  = GND
  CB6_B  = M_E_CPU0_SB_CB<6>
  VSS102  = GND
  CB7_B  = M_E_CPU0_SB_CB<7>
  VSS103  = GND
  DQS4_B_C  = M_E_CPU0_SB_DQS_DN<4>
  DQS4_B_T  = M_E_CPU0_SB_DQS_DP<4>
  VSS104  = GND
  CB2_B  = M_E_CPU0_SB_CB<2>
  VSS105  = GND
  CB3_B  = M_E_CPU0_SB_CB<3>
  VSS106  = GND
  DQ2_B  = M_E_CPU0_SB_DQ<2>
  VSS107  = GND
  DQ3_B  = M_E_CPU0_SB_DQ<3>
  VSS108  = GND
  \dqs5_b_c||tdqs5_b_c\  = M_E_CPU0_SB_DQS_DN<5>
  \dqs5_b_t||tdqs5_b_t\  = M_E_CPU0_SB_DQS_DP<5>
  VSS109  = GND
  DQ6_B  = M_E_CPU0_SB_DQ<6>
  VSS110  = GND
  DQ7_B  = M_E_CPU0_SB_DQ<7>
  VSS111  = GND
  DQ10_B  = M_E_CPU0_SB_DQ<10>
  VSS112  = GND
  DQ11_B  = M_E_CPU0_SB_DQ<11>
  VSS113  = GND
  \dqs6_b_c||tdqs6_b_c\  = M_E_CPU0_SB_DQS_DN<6>
  \dqs6_b_t||tdqs6_b_t\  = M_E_CPU0_SB_DQS_DP<6>
  VSS114  = GND
  DQ14_B  = M_E_CPU0_SB_DQ<14>
  VSS115  = GND
  DQ15_B  = M_E_CPU0_SB_DQ<15>
  VSS116  = GND
  DQ18_B  = M_E_CPU0_SB_DQ<18>
  VSS117  = GND
  DQ19_B  = M_E_CPU0_SB_DQ<19>
  VSS118  = GND
  \dqs7_b_c||tdqs7_b_c\  = M_E_CPU0_SB_DQS_DN<7>
  \dqs7_b_t||tdqs7_b_t\  = M_E_CPU0_SB_DQS_DP<7>
  VSS119  = GND
  DQ22_B  = M_E_CPU0_SB_DQ<22>
  VSS120  = GND
  DQ23_B  = M_E_CPU0_SB_DQ<23>
  VSS121  = GND
  DQ26_B  = M_E_CPU0_SB_DQ<26>
  VSS122  = GND
  DQ27_B  = M_E_CPU0_SB_DQ<27>
  VSS123  = GND
  \dqs8_b_c||tdqs8_b_c\  = M_E_CPU0_SB_DQS_DN<8>
  \dqs8_b_t||tdqs8_b_t\  = M_E_CPU0_SB_DQS_DP<8>
  VSS124  = GND
  DQ30_B  = M_E_CPU0_SB_DQ<30>
  VSS125  = GND
  DQ31_B  = M_E_CPU0_SB_DQ<31>
  VSS126  = GND
  G1  = GND
  G2  = GND
  G3  = GND

(kicad_pcb
	(version 20260206)
	(generator "pcbnew")
	(generator_version "10.0")
	(general
		(thickness 1.6)
		(legacy_teardrops no)
	)
	(paper "A4")
	(title_block
		(title "03242023_DA0F0TMBIJ0_F0T_Motherboard_J_brd_V01_OCP.brd")
		(comment 1 "Grand Teton / footprint 1607 of 6105 (J10), pads 1-45 of 291")
	)
	(layers
		(0 "F.Cu" signal "TOP")
		(4 "In1.Cu" signal "GND")
		(6 "In2.Cu" signal "IN1")
		(8 "In3.Cu" signal "GND1")
		(10 "In4.Cu" signal "IN2")
		(12 "In5.Cu" signal "GND2")
		(14 "In6.Cu" signal "IN3")
		(16 "In7.Cu" signal "GND3")
		(18 "In8.Cu" signal "VCC")
		(20 "In9.Cu" signal "VCC1")
		(22 "In10.Cu" signal "GND4")
		(24 "In11.Cu" signal "IN4")
		(26 "In12.Cu" signal "GND5")
		(28 "In13.Cu" signal "IN5")
		(30 "In14.Cu" signal "GND6")
		(32 "In15.Cu" signal "IN6")
		(34 "In16.Cu" signal "GND7")
		(2 "B.Cu" signal "BOTTOM")
		(9 "F.Adhes" user "F.Adhesive")
		(11 "B.Adhes" user "B.Adhesive")
		(13 "F.Paste" user "Package Geometry/Pastemask Top")
		(15 "B.Paste" user "Package Geometry/Pastemask Bottom")
		(5 "F.SilkS" user "Ref Des/Silkscreen Top")
		(7 "B.SilkS" user "Ref Des/Silkscreen Bottom")
		(1 "F.Mask" user "Board Geometry/Soldermask Top")
		(3 "B.Mask" user "Board Geometry/Soldermask Bottom")
		(17 "Dwgs.User" user "User.Drawings")
		(19 "Cmts.User" user "User.Comments")
		(21 "Eco1.User" user "User.Eco1")
		(23 "Eco2.User" user "User.Eco2")
		(25 "Edge.Cuts" user "Board Geometry/Outline")
		(27 "Margin" user)
		(31 "F.CrtYd" user "Package Geometry/Place Bound Top")
		(29 "B.CrtYd" user "Package Geometry/Place Bound Bottom")
		(35 "F.Fab" user "Ref Des/Assembly Top")
		(33 "B.Fab" user "Ref Des/Assembly Bottom")
	)
	(footprint ""
		(layer "F.Cu")
		(at 408.803348 -258.091686)
		(property "Reference" "J10"
			(at -3.683 -81.702148 0)
			(unlocked yes)
			(layer "F.SilkS")
			(effects
				(font
					(size 0.7874 0.5842)
					(thickness 0.1524)
				)
				(justify left)
			)
		)
		(property "Value" ""
			(at 0 0 0)
			(layer "F.Fab")
			(effects
				(font
					(size 1.27 1.27)
				)
			)
		)
		(duplicate_pad_numbers_are_jumpers no)
		(pad "1" smd rect
			(at -2.050034 -63.324994 270)
			(size 0.519938 1.4986)
			(layers "F.Cu" "F.Mask" "F.Paste")
			(net "P12V_S3_AUX_CPU0_NVDIMM")
		)
		(pad "2" smd rect
			(at -2.050034 -62.47511 270)
			(size 0.519938 1.4986)
			(layers "F.Cu" "F.Mask" "F.Paste")
			(net "TP_CHE_CPU0_DIMM2_FRU_0")
		)
		(pad "3" smd rect
			(at -2.050034 -61.624972 270)
			(size 0.519938 1.4986)
			(layers "F.Cu" "F.Mask" "F.Paste")
			(net "P3V3_AUX")
		)
		(pad "4" smd rect
			(at -2.050034 -60.775088 270)
			(size 0.519938 1.4986)
			(layers "F.Cu" "F.Mask" "F.Paste")
			(net "I3C_SPD_DDREFGH_CPU0_LVC1_SCL_1")
		)
		(pad "5" smd rect
			(at -2.050034 -59.92495 270)
			(size 0.519938 1.4986)
			(layers "F.Cu" "F.Mask" "F.Paste")
			(net "I3C_SPD_DDREFGH_CPU0_LVC1_SDA")
		)
		(pad "6" smd rect
			(at -2.050034 -59.075066 270)
			(size 0.519938 1.4986)
			(layers "F.Cu" "F.Mask" "F.Paste")
			(net "GND")
		)
		(pad "7" smd rect
			(at -2.050034 -58.224928 270)
			(size 0.519938 1.4986)
			(layers "F.Cu" "F.Mask" "F.Paste")
			(net "M_E_CPU0_SA_DQ<0>")
		)
		(pad "8" smd rect
			(at -2.050034 -57.375044 270)
			(size 0.519938 1.4986)
			(layers "F.Cu" "F.Mask" "F.Paste")
			(net "GND")
		)
		(pad "9" smd rect
			(at -2.050034 -56.524906 270)
			(size 0.519938 1.4986)
			(layers "F.Cu" "F.Mask" "F.Paste")
			(net "M_E_CPU0_SA_DQ<1>")
		)
		(pad "10" smd rect
			(at -2.050034 -55.675022 270)
			(size 0.519938 1.4986)
			(layers "F.Cu" "F.Mask" "F.Paste")
			(net "GND")
		)
		(pad "11" smd rect
			(at -2.050034 -54.824884 270)
			(size 0.519938 1.4986)
			(layers "F.Cu" "F.Mask" "F.Paste")
			(net "M_E_CPU0_SA_DQS_DP<0>")
		)
		(pad "12" smd rect
			(at -2.050034 -53.975 270)
			(size 0.519938 1.4986)
			(layers "F.Cu" "F.Mask" "F.Paste")
			(net "M_E_CPU0_SA_DQS_DN<0>")
		)
		(pad "13" smd rect
			(at -2.050034 -53.125116 270)
			(size 0.519938 1.4986)
			(layers "F.Cu" "F.Mask" "F.Paste")
			(net "GND")
		)
		(pad "14" smd rect
			(at -2.050034 -52.274978 270)
			(size 0.519938 1.4986)
			(layers "F.Cu" "F.Mask" "F.Paste")
			(net "M_E_CPU0_SA_DQ<4>")
		)
		(pad "15" smd rect
			(at -2.050034 -51.425094 270)
			(size 0.519938 1.4986)
			(layers "F.Cu" "F.Mask" "F.Paste")
			(net "GND")
		)
		(pad "16" smd rect
			(at -2.050034 -50.574956 270)
			(size 0.519938 1.4986)
			(layers "F.Cu" "F.Mask" "F.Paste")
			(net "M_E_CPU0_SA_DQ<5>")
		)
		(pad "17" smd rect
			(at -2.050034 -49.725072 270)
			(size 0.519938 1.4986)
			(layers "F.Cu" "F.Mask" "F.Paste")
			(net "GND")
		)
		(pad "18" smd rect
			(at -2.050034 -48.874934 270)
			(size 0.519938 1.4986)
			(layers "F.Cu" "F.Mask" "F.Paste")
			(net "M_E_CPU0_SA_DQ<8>")
		)
		(pad "19" smd rect
			(at -2.050034 -48.02505 270)
			(size 0.519938 1.4986)
			(layers "F.Cu" "F.Mask" "F.Paste")
			(net "GND")
		)
		(pad "20" smd rect
			(at -2.050034 -47.174912 270)
			(size 0.519938 1.4986)
			(layers "F.Cu" "F.Mask" "F.Paste")
			(net "M_E_CPU0_SA_DQ<9>")
		)
		(pad "21" smd rect
			(at -2.050034 -46.325028 270)
			(size 0.519938 1.4986)
			(layers "F.Cu" "F.Mask" "F.Paste")
			(net "GND")
		)
		(pad "22" smd rect
			(at -2.050034 -45.47489 270)
			(size 0.519938 1.4986)
			(layers "F.Cu" "F.Mask" "F.Paste")
			(net "M_E_CPU0_SA_DQS_DP<1>")
		)
		(pad "23" smd rect
			(at -2.050034 -44.625006 270)
			(size 0.519938 1.4986)
			(layers "F.Cu" "F.Mask" "F.Paste")
			(net "M_E_CPU0_SA_DQS_DN<1>")
		)
		(pad "24" smd rect
			(at -2.050034 -43.775122 270)
			(size 0.519938 1.4986)
			(layers "F.Cu" "F.Mask" "F.Paste")
			(net "GND")
		)
		(pad "25" smd rect
			(at -2.050034 -42.924984 270)
			(size 0.519938 1.4986)
			(layers "F.Cu" "F.Mask" "F.Paste")
			(net "M_E_CPU0_SA_DQ<12>")
		)
		(pad "26" smd rect
			(at -2.050034 -42.0751 270)
			(size 0.519938 1.4986)
			(layers "F.Cu" "F.Mask" "F.Paste")
			(net "GND")
		)
		(pad "27" smd rect
			(at -2.050034 -41.224962 270)
			(size 0.519938 1.4986)
			(layers "F.Cu" "F.Mask" "F.Paste")
			(net "M_E_CPU0_SA_DQ<13>")
		)
		(pad "28" smd rect
			(at -2.050034 -40.375078 270)
			(size 0.519938 1.4986)
			(layers "F.Cu" "F.Mask" "F.Paste")
			(net "GND")
		)
		(pad "29" smd rect
			(at -2.050034 -39.52494 270)
			(size 0.519938 1.4986)
			(layers "F.Cu" "F.Mask" "F.Paste")
			(net "M_E_CPU0_SA_DQ<16>")
		)
		(pad "30" smd rect
			(at -2.050034 -38.675056 270)
			(size 0.519938 1.4986)
			(layers "F.Cu" "F.Mask" "F.Paste")
			(net "GND")
		)
		(pad "31" smd rect
			(at -2.050034 -37.824918 270)
			(size 0.519938 1.4986)
			(layers "F.Cu" "F.Mask" "F.Paste")
			(net "M_E_CPU0_SA_DQ<17>")
		)
		(pad "32" smd rect
			(at -2.050034 -36.975034 270)
			(size 0.519938 1.4986)
			(layers "F.Cu" "F.Mask" "F.Paste")
			(net "GND")
		)
		(pad "33" smd rect
			(at -2.050034 -36.124896 270)
			(size 0.519938 1.4986)
			(layers "F.Cu" "F.Mask" "F.Paste")
			(net "M_E_CPU0_SA_DQS_DP<2>")
		)
		(pad "34" smd rect
			(at -2.050034 -35.275012 270)
			(size 0.519938 1.4986)
			(layers "F.Cu" "F.Mask" "F.Paste")
			(net "M_E_CPU0_SA_DQS_DN<2>")
		)
		(pad "35" smd rect
			(at -2.050034 -34.425128 270)
			(size 0.519938 1.4986)
			(layers "F.Cu" "F.Mask" "F.Paste")
			(net "GND")
		)
		(pad "36" smd rect
			(at -2.050034 -33.57499 270)
			(size 0.519938 1.4986)
			(layers "F.Cu" "F.Mask" "F.Paste")
			(net "M_E_CPU0_SA_DQ<20>")
		)
		(pad "37" smd rect
			(at -2.050034 -32.725106 270)
			(size 0.519938 1.4986)
			(layers "F.Cu" "F.Mask" "F.Paste")
			(net "GND")
		)
		(pad "38" smd rect
			(at -2.050034 -31.874968 270)
			(size 0.519938 1.4986)
			(layers "F.Cu" "F.Mask" "F.Paste")
			(net "M_E_CPU0_SA_DQ<21>")
		)
		(pad "39" smd rect
			(at -2.050034 -31.025084 270)
			(size 0.519938 1.4986)
			(layers "F.Cu" "F.Mask" "F.Paste")
			(net "GND")
		)
		(pad "40" smd rect
			(at -2.050034 -30.174946 270)
			(size 0.519938 1.4986)
			(layers "F.Cu" "F.Mask" "F.Paste")
			(net "M_E_CPU0_SA_DQ<24>")
		)
		(pad "41" smd rect
			(at -2.050034 -29.325062 270)
			(size 0.519938 1.4986)
			(layers "F.Cu" "F.Mask" "F.Paste")
			(net "GND")
		)
		(pad "42" smd rect
			(at -2.050034 -28.474924 270)
			(size 0.519938 1.4986)
			(layers "F.Cu" "F.Mask" "F.Paste")
			(net "M_E_CPU0_SA_DQ<25>")
		)
		(pad "43" smd rect
			(at -2.050034 -27.62504 270)
			(size 0.519938 1.4986)
			(layers "F.Cu" "F.Mask" "F.Paste")
			(net "GND")
		)
		(pad "44" smd rect
			(at -2.050034 -26.774902 270)
			(size 0.519938 1.4986)
			(layers "F.Cu" "F.Mask" "F.Paste")
			(net "M_E_CPU0_SA_DQS_DP<3>")
		)
		(pad "45" smd rect
			(at -2.050034 -25.925018 270)
			(size 0.519938 1.4986)
			(layers "F.Cu" "F.Mask" "F.Paste")
			(net "M_E_CPU0_SA_DQS_DN<3>")
		)
	)
)
